FILE_TYPE = CONNECTIVITY;
{Allegro Design Entry HDL 16.6-p007 (v16-6-112F) 10/10/2012}
"PAGE_NUMBER" = 99;
0"NC";
1"PVCCIO_CPU0\g";
2"PVPP_DEF\g";
3"PVPP_GHJ\g";
4"PVPP_KLM\g";
5"PVPP_ABC\g";
6"PVPP_ABC\g";
7"PVPP_ABC\g";
8"PVCCIO_CPU0\g";
9"PVCCIO_CPU0\g";
10"PVCCIO_CPU0\g";
11"GND\g";
12"PVCCIO_CPU1\g";
13"GND\g";
14"GND\g";
15"PVPP_DEF\g";
16"GND\g";
17"PVPP_GHJ\g";
18"GND\g";
19"PVCCIO_CPU1\g";
20"GND\g";
21"PVPP_KLM\g";
22"GND\g";
23"PVPP_DEF\g";
24"PVPP_GHJ\g";
25"PVCCIO_CPU0\g";
26"PVCCIO_CPU0\g";
27"PVCCIO_CPU1\g";
28"PVCCIO_CPU1\g";
29"PVPP_KLM\g";
30"PVCCIO_CPU1\g";
31"PVCCIO_CPU1\g";
32"GND\g";
33"SMB_DDR_ABC_SCL_G";
34"SMB_DDR_GHJ_VPP_SDA";
35"SMB_DDR_GHJ_VPP_SCL_R";
36"SMB_DDR_GHJ_VPP_SDA_R";
37"SMB_DDR_KLM_SDA_G_R";
38"SMB_DDR_KLM_SCL_G";
39"SMB_DDR_KLM_SDA_G";
40"TP_SMB_DDR_KLM_EN";
41"SMB_DDR_KLM_SCL_G_R";
42"SMB_DDR_KLM_VPP_SDA";
43"SMB_DDR_KLM_VPP_SCL";
44"TP_SMB_DDR_GHJ_EN";
45"SMB_DDR_GHJ_SCL_G";
46"SMB_DDR_GHJ_SDA_G";
47"SMB_DDR_GHJ_SDA_G_R";
48"SMB_DDR_GHJ_SCL_G_R";
49"SMB_DDR_DEF_SDA_G_R";
50"TP_SMB_DDR_DEF_EN";
51"SMB_DDR_DEF_SCL_G";
52"SMB_DDR_DEF_SDA_G";
53"TP_SMB_DDR_ABC_EN";
54"SMB_DDR_ABC_SDA_G";
55"SMB_DDR_ABC_SDA_G_R";
56"SMB_DDR_ABC_SCL_G_R";
57"SMB_DDR_ABC_VPP_SCL_R";
58"SMB_DDR_ABC_VPP_SDA_R";
59"SMB_DDR_ABC_VPP_SCL";
60"SMB_DDR_ABC_VPP_SDA";
61"SMB_DDR_DEF_VPP_SCL_R";
62"SMB_DDR_DEF_VPP_SDA";
63"SMB_DDR_DEF_VPP_SCL";
64"SMB_DDR_DEF_VPP_SDA_R";
65"SMB_DDR_KLM_VPP_SDA_R";
66"SMB_DDR_KLM_VPP_SCL_R";
67"SMB_DDR_DEF_SCL_G_R";
68"SMB_DDR_GHJ_VPP_SCL";
%"PVCCIO_CPU0"
"1","(1900,5100)","0","mstr_symbols","I1";
;
CDS_LIB"mstr_symbols"
VOLTAGE"1.1V"
BODY_TYPE"PLUMBING"
HDL_POWER"PVCCIO_CPU0";
"G\NAC"1;
%"RES"
"1","(1600,4300)","0","mstr_discrete","I10";
;
LOCATION"R4T10"
VALUE"20.0"
MATERIAL"CHIP"
WATTAGE"1/16W"
TOLERANCE"1%"
PART_NUMBER"G21796-173"
PACK_TYPE"0402"
ROOM"MEM"
CDS_LOCATION"R4T10"
$SEC"1"
CDS_SEC"1"
CDS_LIB"mstr_discrete";
"B"
$PN"2"60;
"A"
$PN"1"58;
%"RES"
"2","(1275,3600)","0","mstr_discrete","I101";
;
CDS_SEC"1"
WATTAGE"1/16W"
MATERIAL"CHIP"
TOLERANCE"1.0%"
VALUE"665"
PART_NUMBER"G21796-235"
LOCATION"R3R12"
PACK_TYPE"0402"
ROOM"MEM"
CDS_LOCATION"R3R12"
SEC"1"
SEC_TYPE"0402"
BOM_COST"SM_CONTROLLER"
CDS_LIB"mstr_discrete";
"A"
$PN"1"2;
"B"
$PN"2"64;
%"PVPP_DEF"
"1","(925,3900)","0","mstr_symbols","I102";
;
ROOM"SMB"
CDS_LIB"mstr_symbols"
BOM_COST"SM_CONTROLLER"
VOLTAGE"2.5V"
BODY_TYPE"PLUMBING"
HDL_POWER"PVPP_DEF";
"G\NAC"2;
%"RES"
"2","(925,3600)","0","mstr_discrete","I103";
;
CDS_SEC"1"
WATTAGE"1/16W"
MATERIAL"CHIP"
PACK_TYPE"0402"
TOLERANCE"1.0%"
VALUE"665"
PART_NUMBER"G21796-235"
LOCATION"R3R5"
ROOM"MEM"
CDS_LOCATION"R3R5"
SEC"1"
SEC_TYPE"0402"
CDS_LIB"mstr_discrete"
BOM_COST"SM_CONTROLLER";
"A"
$PN"1"2;
"B"
$PN"2"61;
%"RES"
"2","(1225,2450)","0","mstr_discrete","I104";
;
CDS_SEC"1"
TOLERANCE"1.0%"
VALUE"665"
MATERIAL"CHIP"
PACK_TYPE"0402"
LOCATION"R6U18"
WATTAGE"1/16W"
PART_NUMBER"G21796-235"
ROOM"MEM"
CDS_LOCATION"R6U18"
SEC"1"
SEC_TYPE"0402"
BOM_COST"SM_CONTROLLER"
CDS_LIB"mstr_discrete";
"A"
$PN"1"3;
"B"
$PN"2"36;
%"PVPP_GHJ"
"1","(875,2750)","0","mstr_symbols","I105";
;
ROOM"SMB"
CDS_LIB"mstr_symbols"
BOM_COST"SM_CONTROLLER"
VOLTAGE"2.5V"
BODY_TYPE"PLUMBING"
HDL_POWER"PVPP_GHJ";
"G\NAC"3;
%"RES"
"2","(875,2450)","0","mstr_discrete","I106";
;
CDS_SEC"1"
WATTAGE"1/16W"
PART_NUMBER"G21796-235"
MATERIAL"CHIP"
LOCATION"R6U17"
VALUE"665"
TOLERANCE"1.0%"
PACK_TYPE"0402"
ROOM"MEM"
CDS_LOCATION"R6U17"
SEC"1"
SEC_TYPE"0402"
CDS_LIB"mstr_discrete"
BOM_COST"SM_CONTROLLER";
"A"
$PN"1"3;
"B"
$PN"2"35;
%"RES"
"2","(1225,1250)","0","mstr_discrete","I107";
;
CDS_SEC"1"
WATTAGE"1/16W"
MATERIAL"CHIP"
PACK_TYPE"0402"
VALUE"665"
LOCATION"R7M6"
TOLERANCE"1.0%"
PART_NUMBER"G21796-235"
ROOM"MEM"
CDS_LOCATION"R7M6"
SEC"1"
SEC_TYPE"0402"
BOM_COST"SM_CONTROLLER"
CDS_LIB"mstr_discrete";
"A"
$PN"1"4;
"B"
$PN"2"65;
%"PVPP_KLM"
"1","(875,1550)","0","mstr_symbols","I108";
;
ROOM"SMB"
CDS_LIB"mstr_symbols"
BOM_COST"SM_CONTROLLER"
VOLTAGE"2.5V"
BODY_TYPE"PLUMBING"
HDL_POWER"PVPP_KLM";
"G\NAC"4;
%"RES"
"2","(875,1250)","0","mstr_discrete","I109";
;
CDS_SEC"1"
WATTAGE"1/16W"
MATERIAL"CHIP"
PACK_TYPE"0402"
TOLERANCE"1.0%"
VALUE"665"
PART_NUMBER"G21796-235"
LOCATION"R7M1"
ROOM"MEM"
CDS_LOCATION"R7M1"
SEC"1"
SEC_TYPE"0402"
CDS_LIB"mstr_discrete"
BOM_COST"SM_CONTROLLER";
"A"
$PN"1"4;
"B"
$PN"2"66;
%"RES"
"2","(1225,4650)","0","mstr_discrete","I11";
;
CDS_SEC"1"
VALUE"665"
LOCATION"R4T8"
TOLERANCE"1.0%"
WATTAGE"1/16W"
PART_NUMBER"G21796-235"
MATERIAL"CHIP"
PACK_TYPE"0402"
ROOM"MEM"
CDS_LOCATION"R4T8"
SEC"1"
SEC_TYPE"0402"
CDS_LIB"mstr_discrete"
BOM_COST"SM_CONTROLLER";
"A"
$PN"1"7;
"B"
$PN"2"58;
%"RES"
"1","(-1175,3250)","0","mstr_discrete","I110";
;
LOCATION"R3R14"
VALUE"10.0"
TOLERANCE"1%"
PACK_TYPE"0402"
MATERIAL"CHIP"
WATTAGE"1/16W"
PART_NUMBER"G21796-066"
ROOM"MEM"
CDS_LOCATION"R3R14"
$SEC"1"
CDS_SEC"1"
BOM_COST"SM_CONTROLLER"
CDS_LIB"mstr_discrete";
"B"
$PN"2"52;
"A"
$PN"1"49;
%"RES"
"1","(-1100,2100)","0","mstr_discrete","I111";
;
PACK_TYPE"0402"
PART_NUMBER"G21796-066"
VALUE"10.0"
LOCATION"R6T4"
TOLERANCE"1%"
WATTAGE"1/16W"
MATERIAL"CHIP"
ROOM"MEM"
CDS_LOCATION"R6T4"
$SEC"1"
CDS_SEC"1"
BOM_COST"SM_CONTROLLER"
CDS_LIB"mstr_discrete";
"B"
$PN"2"46;
"A"
$PN"1"47;
%"RES"
"1","(-1200,900)","0","mstr_discrete","I112";
;
PACK_TYPE"0402"
PART_NUMBER"G21796-066"
MATERIAL"CHIP"
WATTAGE"1/16W"
TOLERANCE"1%"
LOCATION"R7M8"
VALUE"10.0"
ROOM"MEM"
CDS_LOCATION"R7M8"
$SEC"1"
CDS_SEC"1"
CDS_LIB"mstr_discrete"
BOM_COST"SM_CONTROLLER";
"B"
$PN"2"39;
"A"
$PN"1"37;
%"PVPP_ABC"
"1","(1475,5100)","0","mstr_symbols","I113";
;
ROOM"SMB"
CDS_LIB"mstr_symbols"
BOM_COST"SM_CONTROLLER"
VOLTAGE"2.5V"
BODY_TYPE"PLUMBING"
HDL_POWER"PVPP_ABC";
"G\NAC"5;
%"PVPP_ABC"
"1","(650,4625)","0","mstr_symbols","I114";
;
ROOM"SMB"
CDS_LIB"mstr_symbols"
BOM_COST"SM_CONTROLLER"
VOLTAGE"2.5V"
BODY_TYPE"PLUMBING"
HDL_POWER"PVPP_ABC";
"G\NAC"6;
%"RES"
"1","(1600,2100)","0","mstr_discrete","I115";
;
MATERIAL"CHIP"
PART_NUMBER"G21796-173"
PACK_TYPE"0402"
LOCATION"R6U14"
WATTAGE"1/16W"
TOLERANCE"1%"
VALUE"20.0"
ROOM"MEM"
$SEC"1"
CDS_SEC"1"
CDS_LIB"mstr_discrete"
CDS_LOCATION"R6U14";
"B"
$PN"2"34;
"A"
$PN"1"36;
%"PVPP_ABC"
"1","(875,4950)","0","mstr_symbols","I12";
;
ROOM"SMB"
CDS_LIB"mstr_symbols"
BOM_COST"SM_CONTROLLER"
VOLTAGE"2.5V"
BODY_TYPE"PLUMBING"
HDL_POWER"PVPP_ABC";
"G\NAC"7;
%"RES"
"2","(875,4650)","0","mstr_discrete","I13";
;
CDS_SEC"1"
PART_NUMBER"G21796-235"
MATERIAL"CHIP"
PACK_TYPE"0402"
WATTAGE"1/16W"
TOLERANCE"1.0%"
LOCATION"R4T7"
VALUE"665"
ROOM"MEM"
CDS_LOCATION"R4T7"
SEC"1"
SEC_TYPE"0402"
BOM_COST"SM_CONTROLLER"
CDS_LIB"mstr_discrete";
"A"
$PN"1"7;
"B"
$PN"2"57;
%"PCA9617"
"1","(150,4300)","0","mstr_digital","I15";
;
MATERIAL"IC"
PART_NUMBER"G81764-001"
LOCATION"U6F1"
POWER_GROUP"GND=GND"
ROOM"MEM"
CDS_LOCATION"U6F1"
$SEC"1"
CDS_SEC"1"
BOM_COST"SM_CONTROLLER"
CDS_LIB"mstr_digital"
PACK_TYPE"SSOP";
"VCCA"
$PN"1"8;
"SCLA"
$PN"2"33;
"SDAA"
$PN"3"54;
"SCLB"
$PN"7"57;
"SDAB"
$PN"6"58;
"VCCB"
$PN"8"6;
"EN"
$PN"5"53;
%"PVCCIO_CPU0"
"1","(-475,4875)","0","mstr_symbols","I16";
;
CDS_LIB"mstr_symbols"
VOLTAGE"1.1V"
BODY_TYPE"PLUMBING"
HDL_POWER"PVCCIO_CPU0";
"G\NAC"8;
%"RES"
"2","(-650,4650)","2","mstr_discrete","I17";
;
VALUE"240"
LOCATION"R4T6"
TOLERANCE"1.0%"
WATTAGE"1/16W"
MATERIAL"CHIP"
PART_NUMBER"G21796-294"
PACK_TYPE"0402"
ROOM"MEM"
CDS_LOCATION"R4T6"
$SEC"1"
CDS_SEC"1"
BOM_COST"SM_CONTROLLER"
CD_SEC"1"
SIGNAL_MODEL"DEFAULT_RESISTOR_750OHM_2_1"
CDS_LIB"mstr_discrete";
"A"
$PN"1"9;
"B"
$PN"2"54;
%"PVCCIO_CPU0"
"1","(-900,4975)","0","mstr_symbols","I18";
;
CDS_LIB"mstr_symbols"
VOLTAGE"1.1V"
BODY_TYPE"PLUMBING"
HDL_POWER"PVCCIO_CPU0";
"G\NAC"9;
%"RES"
"2","(-1025,4650)","2","mstr_discrete","I19";
;
PART_NUMBER"G21796-294"
LOCATION"R4T5"
VALUE"240"
WATTAGE"1/16W"
MATERIAL"CHIP"
TOLERANCE"1.0%"
PACK_TYPE"0402"
ROOM"MEM"
CDS_LOCATION"R4T5"
$SEC"1"
CDS_SEC"1"
BOM_COST"SM_CONTROLLER"
CDS_LIB"mstr_discrete"
SIGNAL_MODEL"DEFAULT_RESISTOR_750OHM_2_1"
CD_SEC"1";
"A"
$PN"1"9;
"B"
$PN"2"33;
%"CAP_A"
"1","(1900,4925)","0","dev_discrete","I2";
;
PACK_TYPE"0402V"
PART_NUMBER"A36096-030"
TOLERANCE"10%"
VOLTAGE"16V"
VALUE"0.1UF"
LOCATION"C6F2"
MATERIAL"X7R"
$SEC"1"
CDS_SEC"1"
CDS_LIB"dev_discrete"
SIGNAL_MODEL"DEFAULT_CAPACITOR_100000pF_2_1"
CD_SEC"1"
BOM_COST"SM_CONTROLLER"
CDS_LOCATION"C6F2"
ROOM"MEM";
"B"
$PN"2"14;
"A"
$PN"1"1;
%"RES"
"1","(-1075,4300)","0","mstr_discrete","I20";
;
LOCATION"R4T4"
MATERIAL"CHIP"
PACK_TYPE"0402"
TOLERANCE"1%"
VALUE"10.0"
PART_NUMBER"G21796-066"
WATTAGE"1/16W"
ROOM"MEM"
CDS_LOCATION"R4T4"
$SEC"1"
CDS_SEC"1"
BOM_COST"SM_CONTROLLER"
CDS_LIB"mstr_discrete";
"B"
$PN"2"54;
"A"
$PN"1"55;
%"PVCCIO_CPU0"
"1","(2125,3950)","0","mstr_symbols","I21";
;
CDS_LIB"mstr_symbols"
VOLTAGE"1.1V"
BODY_TYPE"PLUMBING"
HDL_POWER"PVCCIO_CPU0";
"G\NAC"10;
%"GND"
"1","(2125,3525)","0","mstr_symbols","I22";
;
ROOM"SMB"
SIZE"1B"
CDS_LIB"mstr_symbols"
BOM_COST"SM_CONTROLLER"
VOLTAGE"0"
BODY_TYPE"PLUMBING"
HDL_POWER"GND";
"A\NAC"11;
%"CAP_A"
"1","(2125,3775)","0","dev_discrete","I23";
;
MATERIAL"X7R"
VOLTAGE"16V"
PACK_TYPE"0402V"
TOLERANCE"10%"
VALUE"0.1UF"
LOCATION"C7E1"
PART_NUMBER"A36096-030"
$SEC"1"
CDS_SEC"1"
CDS_LIB"dev_discrete"
BOM_COST"SM_CONTROLLER"
CD_SEC"1"
SIGNAL_MODEL"DEFAULT_CAPACITOR_100000pF_2_1"
CDS_LOCATION"C7E1"
ROOM"MEM";
"B"
$PN"2"11;
"A"
$PN"1"10;
%"PVCCIO_CPU1"
"1","(2225,2875)","0","mstr_symbols","I26";
;
CDS_LIB"mstr_symbols"
VOLTAGE"1.1V"
BODY_TYPE"PLUMBING"
HDL_POWER"PVCCIO_CPU1";
"G\NAC"12;
%"CAP_A"
"1","(2225,2700)","0","dev_discrete","I27";
;
PACK_TYPE"0402V"
PART_NUMBER"A36096-030"
MATERIAL"X7R"
TOLERANCE"10%"
VOLTAGE"16V"
VALUE"0.1UF"
LOCATION"C4G22"
$SEC"1"
CDS_SEC"1"
CDS_LIB"dev_discrete"
BOM_COST"SM_CONTROLLER"
CD_SEC"1"
SIGNAL_MODEL"DEFAULT_CAPACITOR_100000pF_2_1"
CDS_LOCATION"C4G22"
ROOM"MEM";
"B"
$PN"2"13;
"A"
$PN"1"12;
%"GND"
"1","(2225,2450)","0","mstr_symbols","I28";
;
ROOM"SMB"
SIZE"1B"
CDS_LIB"mstr_symbols"
BOM_COST"SM_CONTROLLER"
VOLTAGE"0"
BODY_TYPE"PLUMBING"
HDL_POWER"GND";
"A\NAC"13;
%"GND"
"1","(1900,4675)","0","mstr_symbols","I3";
;
ROOM"SMB"
BOM_COST"SM_CONTROLLER"
CDS_LIB"mstr_symbols"
SIZE"1B"
VOLTAGE"0"
BODY_TYPE"PLUMBING"
HDL_POWER"GND";
"A\NAC"14;
%"PVPP_DEF"
"1","(1625,3950)","0","mstr_symbols","I31";
;
CDS_LIB"mstr_symbols"
VOLTAGE"2.5V"
BODY_TYPE"PLUMBING"
HDL_POWER"PVPP_DEF";
"G\NAC"15;
%"CAP_A"
"1","(1625,3750)","0","dev_discrete","I32";
;
MATERIAL"X7R"
VOLTAGE"16V"
TOLERANCE"10%"
VALUE"0.1UF"
PART_NUMBER"A36096-030"
LOCATION"C7E2"
PACK_TYPE"0402V"
$SEC"1"
CDS_SEC"1"
CDS_LIB"dev_discrete"
BOM_COST"SM_CONTROLLER"
SIGNAL_MODEL"DEFAULT_CAPACITOR_100000pF_2_1"
CD_SEC"1"
CDS_LOCATION"C7E2"
ROOM"MEM";
"B"
$PN"2"16;
"A"
$PN"1"15;
%"GND"
"1","(1625,3500)","0","mstr_symbols","I33";
;
ROOM"SMB"
CDS_LIB"mstr_symbols"
SIZE"1B"
VOLTAGE"0"
BODY_TYPE"PLUMBING"
HDL_POWER"GND";
"A\NAC"16;
%"RES"
"1","(1600,3250)","0","mstr_discrete","I34";
;
WATTAGE"1/16W"
MATERIAL"CHIP"
PACK_TYPE"0402"
TOLERANCE"1%"
VALUE"20.0"
PART_NUMBER"G21796-173"
LOCATION"R3R9"
ROOM"MEM"
CDS_LOCATION"R3R9"
$SEC"1"
CDS_SEC"1"
CDS_LIB"mstr_discrete";
"B"
$PN"2"62;
"A"
$PN"1"64;
%"RES"
"1","(1600,3300)","0","mstr_discrete","I35";
;
WATTAGE"1/16W"
MATERIAL"CHIP"
PACK_TYPE"0402"
TOLERANCE"1%"
VALUE"20.0"
PART_NUMBER"G21796-173"
LOCATION"R3R8"
ROOM"MEM"
CDS_LOCATION"R3R8"
$SEC"1"
CDS_SEC"1"
CDS_LIB"mstr_discrete";
"B"
$PN"2"63;
"A"
$PN"1"61;
%"PVPP_GHJ"
"1","(1650,2875)","0","mstr_symbols","I39";
;
ROOM"SMB"
CDS_LIB"mstr_symbols"
BOM_COST"SM_CONTROLLER"
VOLTAGE"2.5V"
BODY_TYPE"PLUMBING"
HDL_POWER"PVPP_GHJ";
"G\NAC"17;
%"GND"
"1","(1650,2425)","0","mstr_symbols","I40";
;
ROOM"SMB"
BOM_COST"SM_CONTROLLER"
CDS_LIB"mstr_symbols"
SIZE"1B"
VOLTAGE"0"
BODY_TYPE"PLUMBING"
HDL_POWER"GND";
"A\NAC"18;
%"CAP_A"
"1","(1650,2675)","0","dev_discrete","I41";
;
PACK_TYPE"0402V"
TOLERANCE"10%"
VOLTAGE"16V"
PART_NUMBER"A36096-030"
MATERIAL"X7R"
VALUE"0.1UF"
LOCATION"C4G25"
$SEC"1"
CDS_SEC"1"
CDS_LIB"dev_discrete"
CD_SEC"1"
SIGNAL_MODEL"DEFAULT_CAPACITOR_100000pF_2_1"
BOM_COST"SM_CONTROLLER"
CDS_LOCATION"C4G25"
ROOM"MEM";
"B"
$PN"2"18;
"A"
$PN"1"17;
%"RES"
"1","(1600,2150)","0","mstr_discrete","I42";
;
PART_NUMBER"G21796-173"
PACK_TYPE"0402"
WATTAGE"1/16W"
TOLERANCE"1%"
MATERIAL"CHIP"
VALUE"20.0"
LOCATION"R6U13"
ROOM"MEM"
CDS_LOCATION"R6U13"
$SEC"1"
CDS_SEC"1"
CDS_LIB"mstr_discrete";
"B"
$PN"2"68;
"A"
$PN"1"35;
%"CAP_A"
"1","(2250,1525)","0","dev_discrete","I47";
;
VALUE"0.1UF"
MATERIAL"X7R"
VOLTAGE"16V"
TOLERANCE"10%"
LOCATION"C3B4"
PART_NUMBER"A36096-030"
PACK_TYPE"0402V"
$SEC"1"
CDS_SEC"1"
CDS_LIB"dev_discrete"
BOM_COST"SM_CONTROLLER"
SIGNAL_MODEL"DEFAULT_CAPACITOR_100000pF_2_1"
CD_SEC"1"
CDS_LOCATION"C3B4"
ROOM"MEM";
"B"
$PN"2"20;
"A"
$PN"1"19;
%"PVCCIO_CPU1"
"1","(2250,1700)","0","mstr_symbols","I48";
;
CDS_LIB"mstr_symbols"
VOLTAGE"1.1V"
BODY_TYPE"PLUMBING"
HDL_POWER"PVCCIO_CPU1";
"G\NAC"19;
%"GND"
"1","(2250,1275)","0","mstr_symbols","I49";
;
ROOM"SMB"
SIZE"1B"
CDS_LIB"mstr_symbols"
BOM_COST"SM_CONTROLLER"
VOLTAGE"0"
BODY_TYPE"PLUMBING"
HDL_POWER"GND";
"A\NAC"20;
%"PVPP_KLM"
"1","(1675,1700)","0","mstr_symbols","I52";
;
ROOM"SMB"
CDS_LIB"mstr_symbols"
BOM_COST"SM_CONTROLLER"
VOLTAGE"2.5V"
BODY_TYPE"PLUMBING"
HDL_POWER"PVPP_KLM";
"G\NAC"21;
%"CAP_A"
"1","(1675,1500)","0","dev_discrete","I53";
;
MATERIAL"X7R"
PACK_TYPE"0402V"
VOLTAGE"16V"
TOLERANCE"10%"
PART_NUMBER"A36096-030"
VALUE"0.1UF"
LOCATION"C3B5"
$SEC"1"
CDS_SEC"1"
CDS_LIB"dev_discrete"
SIGNAL_MODEL"DEFAULT_CAPACITOR_100000pF_2_1"
CD_SEC"1"
BOM_COST"SM_CONTROLLER"
CDS_LOCATION"C3B5"
ROOM"MEM";
"B"
$PN"2"22;
"A"
$PN"1"21;
%"GND"
"1","(1675,1250)","0","mstr_symbols","I54";
;
ROOM"SMB"
BOM_COST"SM_CONTROLLER"
SIZE"1B"
CDS_LIB"mstr_symbols"
VOLTAGE"0"
BODY_TYPE"PLUMBING"
HDL_POWER"GND";
"A\NAC"22;
%"RES"
"1","(1600,900)","0","mstr_discrete","I55";
;
MATERIAL"CHIP"
PACK_TYPE"0402"
VALUE"20.0"
LOCATION"R7M5"
TOLERANCE"1%"
PART_NUMBER"G21796-173"
WATTAGE"1/16W"
ROOM"MEM"
CDS_LOCATION"R7M5"
$SEC"1"
CDS_SEC"1"
CDS_LIB"mstr_discrete";
"B"
$PN"2"42;
"A"
$PN"1"65;
%"RES"
"1","(1600,950)","0","mstr_discrete","I56";
;
MATERIAL"CHIP"
PART_NUMBER"G21796-173"
TOLERANCE"1%"
WATTAGE"1/16W"
VALUE"20.0"
LOCATION"R7M4"
PACK_TYPE"0402"
ROOM"MEM"
CDS_LOCATION"R7M4"
$SEC"1"
CDS_SEC"1"
CDS_LIB"mstr_discrete";
"B"
$PN"2"43;
"A"
$PN"1"66;
%"PVPP_DEF"
"1","(625,3575)","0","mstr_symbols","I60";
;
ROOM"SMB"
CDS_LIB"mstr_symbols"
BOM_COST"SM_CONTROLLER"
VOLTAGE"2.5V"
BODY_TYPE"PLUMBING"
HDL_POWER"PVPP_DEF";
"G\NAC"23;
%"PCA9617"
"1","(150,3250)","0","mstr_digital","I61";
;
MATERIAL"IC"
PART_NUMBER"G81764-001"
LOCATION"U7E1"
POWER_GROUP"GND=GND"
ROOM"MEM"
CDS_LOCATION"U7E1"
$SEC"1"
CDS_SEC"1"
BOM_COST"SM_CONTROLLER"
CDS_LIB"mstr_digital"
PACK_TYPE"SSOP";
"VCCA"
$PN"1"25;
"SCLA"
$PN"2"51;
"SDAA"
$PN"3"52;
"SCLB"
$PN"7"61;
"SDAB"
$PN"6"64;
"VCCB"
$PN"8"23;
"EN"
$PN"5"50;
%"PVPP_GHJ"
"1","(600,2425)","0","mstr_symbols","I62";
;
ROOM"SMB"
CDS_LIB"mstr_symbols"
BOM_COST"SM_CONTROLLER"
VOLTAGE"2.5V"
BODY_TYPE"PLUMBING"
HDL_POWER"PVPP_GHJ";
"G\NAC"24;
%"PCA9617"
"1","(150,2100)","0","mstr_digital","I63";
;
MATERIAL"IC"
PART_NUMBER"G81764-001"
LOCATION"U4G1"
POWER_GROUP"GND=GND"
ROOM"MEM"
CDS_LOCATION"U4G1"
$SEC"1"
CDS_SEC"1"
BOM_COST"SM_CONTROLLER"
CDS_LIB"mstr_digital"
PACK_TYPE"SSOP";
"VCCA"
$PN"1"27;
"SCLA"
$PN"2"45;
"SDAA"
$PN"3"46;
"SCLB"
$PN"7"35;
"SDAB"
$PN"6"36;
"VCCB"
$PN"8"24;
"EN"
$PN"5"44;
%"PVCCIO_CPU0"
"1","(-500,3825)","0","mstr_symbols","I64";
;
CDS_LIB"mstr_symbols"
VOLTAGE"1.1V"
BODY_TYPE"PLUMBING"
HDL_POWER"PVCCIO_CPU0";
"G\NAC"25;
%"RES"
"2","(-675,3600)","2","mstr_discrete","I65";
;
WATTAGE"1/16W"
MATERIAL"CHIP"
PACK_TYPE"0402"
TOLERANCE"1.0%"
VALUE"240"
PART_NUMBER"G21796-294"
LOCATION"R3R13"
ROOM"MEM"
CDS_LOCATION"R3R13"
$SEC"1"
CDS_SEC"1"
BOM_COST"SM_CONTROLLER"
CD_SEC"1"
SIGNAL_MODEL"DEFAULT_RESISTOR_750OHM_2_1"
CDS_LIB"mstr_discrete";
"A"
$PN"1"26;
"B"
$PN"2"52;
%"PVCCIO_CPU0"
"1","(-925,3925)","0","mstr_symbols","I66";
;
CDS_LIB"mstr_symbols"
VOLTAGE"1.1V"
BODY_TYPE"PLUMBING"
HDL_POWER"PVCCIO_CPU0";
"G\NAC"26;
%"RES"
"2","(-1050,3600)","2","mstr_discrete","I67";
;
CDS_LOCATION"R3P60"
LOCATION"R3P60"
VALUE"240"
TOLERANCE"1.0%"
MATERIAL"CHIP"
PACK_TYPE"0402"
WATTAGE"1/16W"
PART_NUMBER"G21796-294"
ROOM"MEM"
$SEC"1"
CDS_SEC"1"
BOM_COST"SM_CONTROLLER"
CDS_LIB"mstr_discrete"
SIGNAL_MODEL"DEFAULT_RESISTOR_750OHM_2_1"
CD_SEC"1";
"A"
$PN"1"26;
"B"
$PN"2"51;
%"PVCCIO_CPU1"
"1","(-525,2675)","0","mstr_symbols","I69";
;
CDS_LIB"mstr_symbols"
VOLTAGE"1.1V"
BODY_TYPE"PLUMBING"
HDL_POWER"PVCCIO_CPU1";
"G\NAC"27;
%"CAP_A"
"1","(1475,4900)","0","dev_discrete","I7";
;
PACK_TYPE"0402V"
PART_NUMBER"A36096-030"
MATERIAL"X7R"
TOLERANCE"10%"
VOLTAGE"16V"
VALUE"0.1UF"
LOCATION"C6F3"
$SEC"1"
CDS_SEC"1"
CDS_LIB"dev_discrete"
SIGNAL_MODEL"DEFAULT_CAPACITOR_100000pF_2_1"
CD_SEC"1"
BOM_COST"SM_CONTROLLER"
CDS_LOCATION"C6F3"
ROOM"MEM";
"B"
$PN"2"32;
"A"
$PN"1"5;
%"RES"
"2","(-700,2450)","2","mstr_discrete","I70";
;
WATTAGE"1/16W"
MATERIAL"CHIP"
PACK_TYPE"0402"
TOLERANCE"1.0%"
VALUE"240"
LOCATION"R6T1"
PART_NUMBER"G21796-294"
ROOM"MEM"
CDS_LOCATION"R6T1"
$SEC"1"
CDS_SEC"1"
BOM_COST"SM_CONTROLLER"
SIGNAL_MODEL"DEFAULT_RESISTOR_750OHM_2_1"
CD_SEC"1"
CDS_LIB"mstr_discrete";
"A"
$PN"1"28;
"B"
$PN"2"46;
%"PVCCIO_CPU1"
"1","(-950,2775)","0","mstr_symbols","I71";
;
CDS_LIB"mstr_symbols"
VOLTAGE"1.1V"
BODY_TYPE"PLUMBING"
HDL_POWER"PVCCIO_CPU1";
"G\NAC"28;
%"RES"
"2","(-1075,2450)","2","mstr_discrete","I72";
;
PART_NUMBER"G21796-294"
WATTAGE"1/16W"
MATERIAL"CHIP"
PACK_TYPE"0402"
TOLERANCE"1.0%"
VALUE"240"
LOCATION"R6T2"
ROOM"MEM"
CDS_LOCATION"R6T2"
$SEC"1"
CDS_SEC"1"
BOM_COST"SM_CONTROLLER"
CD_SEC"1"
SIGNAL_MODEL"DEFAULT_RESISTOR_750OHM_2_1"
CDS_LIB"mstr_discrete";
"A"
$PN"1"28;
"B"
$PN"2"45;
%"PVPP_KLM"
"1","(575,1225)","0","mstr_symbols","I74";
;
ROOM"SMB"
CDS_LIB"mstr_symbols"
BOM_COST"SM_CONTROLLER"
VOLTAGE"2.5V"
BODY_TYPE"PLUMBING"
HDL_POWER"PVPP_KLM";
"G\NAC"29;
%"PCA9617"
"1","(150,900)","0","mstr_digital","I75";
;
MATERIAL"IC"
PART_NUMBER"G81764-001"
LOCATION"U3B1"
POWER_GROUP"GND=GND"
ROOM"MEM"
CDS_LOCATION"U3B1"
$SEC"1"
CDS_SEC"1"
BOM_COST"SM_CONTROLLER"
CDS_LIB"mstr_digital"
PACK_TYPE"SSOP";
"VCCA"
$PN"1"30;
"SCLA"
$PN"2"38;
"SDAA"
$PN"3"39;
"SCLB"
$PN"7"66;
"SDAB"
$PN"6"65;
"VCCB"
$PN"8"29;
"EN"
$PN"5"40;
%"PVCCIO_CPU1"
"1","(-550,1475)","0","mstr_symbols","I76";
;
CDS_LIB"mstr_symbols"
VOLTAGE"1.1V"
BODY_TYPE"PLUMBING"
HDL_POWER"PVCCIO_CPU1";
"G\NAC"30;
%"RES"
"2","(-725,1250)","2","mstr_discrete","I77";
;
WATTAGE"1/16W"
MATERIAL"CHIP"
PACK_TYPE"0402"
TOLERANCE"1.0%"
VALUE"240"
PART_NUMBER"G21796-294"
LOCATION"R7M7"
ROOM"MEM"
CDS_LOCATION"R7M7"
$SEC"1"
CDS_SEC"1"
BOM_COST"SM_CONTROLLER"
SIGNAL_MODEL"DEFAULT_RESISTOR_750OHM_2_1"
CD_SEC"1"
CDS_LIB"mstr_discrete";
"A"
$PN"1"31;
"B"
$PN"2"39;
%"PVCCIO_CPU1"
"1","(-975,1575)","0","mstr_symbols","I78";
;
CDS_LIB"mstr_symbols"
VOLTAGE"1.1V"
BODY_TYPE"PLUMBING"
HDL_POWER"PVCCIO_CPU1";
"G\NAC"31;
%"RES"
"2","(-1100,1250)","2","mstr_discrete","I79";
;
WATTAGE"1/16W"
MATERIAL"CHIP"
TOLERANCE"1.0%"
VALUE"240"
PART_NUMBER"G21796-294"
LOCATION"R7M2"
PACK_TYPE"0402"
ROOM"MEM"
CDS_LOCATION"R7M2"
$SEC"1"
CDS_SEC"1"
BOM_COST"SM_CONTROLLER"
SIGNAL_MODEL"DEFAULT_RESISTOR_750OHM_2_1"
CD_SEC"1"
CDS_LIB"mstr_discrete";
"A"
$PN"1"31;
"B"
$PN"2"38;
%"GND"
"1","(1475,4650)","0","mstr_symbols","I8";
;
ROOM"SMB"
SIZE"1B"
CDS_LIB"mstr_symbols"
BOM_COST"SM_CONTROLLER"
VOLTAGE"0"
BODY_TYPE"PLUMBING"
HDL_POWER"GND";
"A\NAC"32;
%"RES"
"1","(-1500,4350)","0","mstr_discrete","I83";
;
PART_NUMBER"G21796-066"
WATTAGE"1/16W"
PACK_TYPE"0402"
TOLERANCE"1%"
MATERIAL"CHIP"
LOCATION"R4T3"
VALUE"10.0"
ROOM"MEM"
CDS_LOCATION"R4T3"
$SEC"1"
CDS_SEC"1"
CDS_LIB"mstr_discrete"
BOM_COST"SM_CONTROLLER";
"B"
$PN"2"33;
"A"
$PN"1"56;
%"RES"
"1","(-1575,3300)","0","mstr_discrete","I88";
;
PACK_TYPE"0402"
TOLERANCE"1%"
LOCATION"R3R7"
MATERIAL"CHIP"
VALUE"10.0"
PART_NUMBER"G21796-066"
WATTAGE"1/16W"
ROOM"MEM"
CDS_LOCATION"R3R7"
$SEC"1"
CDS_SEC"1"
BOM_COST"SM_CONTROLLER"
CDS_LIB"mstr_discrete";
"B"
$PN"2"51;
"A"
$PN"1"67;
%"RES"
"1","(1600,4350)","0","mstr_discrete","I9";
;
LOCATION"R4T9"
VALUE"20.0"
WATTAGE"1/16W"
PART_NUMBER"G21796-173"
MATERIAL"CHIP"
PACK_TYPE"0402"
TOLERANCE"1%"
ROOM"MEM"
CDS_LOCATION"R4T9"
$SEC"1"
CDS_SEC"1"
CDS_LIB"mstr_discrete";
"B"
$PN"2"59;
"A"
$PN"1"57;
%"RES"
"1","(-1475,2150)","0","mstr_discrete","I92";
;
MATERIAL"CHIP"
PART_NUMBER"G21796-066"
PACK_TYPE"0402"
VALUE"10.0"
WATTAGE"1/16W"
TOLERANCE"1%"
LOCATION"R6T3"
CDS_LIB"mstr_discrete"
BOM_COST"SM_CONTROLLER"
CDS_SEC"1"
$SEC"1"
CDS_LOCATION"R6T3"
ROOM"MEM";
"B"
$PN"2"45;
"A"
$PN"1"48;
%"RES"
"1","(-1575,950)","0","mstr_discrete","I98";
;
LOCATION"R7M3"
TOLERANCE"1%"
WATTAGE"1/16W"
VALUE"10.0"
PACK_TYPE"0402"
PART_NUMBER"G21796-066"
MATERIAL"CHIP"
ROOM"MEM"
CDS_LOCATION"R7M3"
$SEC"1"
CDS_SEC"1"
CDS_LIB"mstr_discrete"
BOM_COST"SM_CONTROLLER";
"B"
$PN"2"38;
"A"
$PN"1"41;
END.
